FILE_TYPE = MACRO_DRAWING;
SET COLOR_WIRE YELLOW;
SET COLOR_PROP ORANGE;
SET COLOR_DOT WHITE;
SET COLOR_ARC YELLOW;
SET COLOR_BODY GREEN;
SET COLOR_NOTE PURPLE;
SET PROP_DISPLAY VALUE;
SET PAGE_NUMBER P3;
FORCEADD QUANTA_TITLE_BLOCK_C..2
(3800 -2200);
FORCEPROP 1 LAST Q_TITLE TABLE OF CONTENT 2/3
J 0
(-5516 -2149);
DISPLAY 2.446809 (-5516 -2149);
PAINT GREEN (-5516 -2149);
FORCEPROP 2 LAST Q_DESIGNER SEAN
J 0
(601 -2049);
DISPLAY 0.978723 (601 -2049);
PAINT GREEN (601 -2049);
FORCEPROP 1 LAST CUSTOM_TXT_CDS <CON_PAGE_NUM> OF <CON_TOTAL_PAGES>
J 0
(3362 -2187);
DISPLAY 0.978723 (3362 -2187);
FORCEPROP 1 LAST CUSTOM_TXT_CDS <Q_REV>
J 0
(3625 -2100);
DISPLAY 1.212766 (3625 -2100);
FORCEPROP 1 LAST CUSTOM_TXT_CDS <Q_PROJ>
J 0
(1425 -2100);
DISPLAY 1.212766 (1425 -2100);
FORCEPROP 1 LAST CUSTOM_TXT_CDS <Q_NUMBER>
J 0
(2400 -2100);
DISPLAY 1.212766 (2400 -2100);
FORCEPROP 1 LAST CUSTOM_TXT_CDS <CON_TC_SNO120>
J 2
(1100 -525);
FORCEPROP 1 LAST CUSTOM_TXT_CDS <CON_TC_SNO119>
J 2
(1100 -425);
FORCEPROP 1 LAST CUSTOM_TXT_CDS <CON_TC_SNO118>
J 2
(1100 -325);
FORCEPROP 1 LAST CUSTOM_TXT_CDS <CON_TC_SNO117>
J 2
(1100 -225);
FORCEPROP 1 LAST CUSTOM_TXT_CDS <CON_TC_SNO116>
J 2
(1100 -125);
FORCEPROP 1 LAST CUSTOM_TXT_CDS <CON_TC_SNO115>
J 2
(1100 -25);
FORCEPROP 1 LAST CUSTOM_TXT_CDS <CON_TC_SNO114>
J 2
(1100 75);
FORCEPROP 1 LAST CUSTOM_TXT_CDS <CON_TC_SNO113>
J 2
(1100 175);
FORCEPROP 1 LAST CUSTOM_TXT_CDS <CON_TC_SNO112>
J 2
(1100 275);
FORCEPROP 1 LAST CUSTOM_TXT_CDS <CON_TC_SNO111>
J 2
(1100 375);
FORCEPROP 1 LAST CUSTOM_TXT_CDS <CON_TC_SNO110>
J 2
(1100 475);
FORCEPROP 1 LAST CUSTOM_TXT_CDS <CON_TC_SNO109>
J 2
(1100 575);
FORCEPROP 1 LAST CUSTOM_TXT_CDS <CON_TC_SNO108>
J 2
(1100 675);
FORCEPROP 1 LAST CUSTOM_TXT_CDS <CON_TC_SNO107>
J 2
(1100 775);
FORCEPROP 1 LAST CUSTOM_TXT_CDS <CON_TC_SNO106>
J 2
(1100 875);
FORCEPROP 1 LAST CUSTOM_TXT_CDS <CON_TC_SNO105>
J 2
(1100 975);
FORCEPROP 1 LAST CUSTOM_TXT_CDS <CON_TC_SNO104>
J 2
(1100 1075);
FORCEPROP 1 LAST CUSTOM_TXT_CDS <CON_TC_SNO103>
J 2
(1100 1175);
FORCEPROP 1 LAST CUSTOM_TXT_CDS <CON_TC_SNO102>
J 2
(1100 1275);
FORCEPROP 1 LAST CUSTOM_TXT_CDS <CON_TC_SNO101>
J 2
(1100 1375);
FORCEPROP 1 LAST CUSTOM_TXT_CDS <CON_TC_SNO100>
J 2
(1100 1475);
FORCEPROP 1 LAST CUSTOM_TXT_CDS <CON_TC_SNO99>
J 2
(1100 1575);
FORCEPROP 1 LAST CUSTOM_TXT_CDS <CON_TC_SNO98>
J 2
(1100 1675);
FORCEPROP 1 LAST CUSTOM_TXT_CDS <CON_TC_SNO97>
J 2
(1100 1775);
FORCEPROP 1 LAST CUSTOM_TXT_CDS <CON_TC_SNO96>
J 2
(1100 1875);
FORCEPROP 1 LAST CUSTOM_TXT_CDS <CON_TC_SNO95>
J 2
(1100 1975);
FORCEPROP 1 LAST CUSTOM_TXT_CDS <CON_TC_SNO94>
J 2
(1100 2075);
FORCEPROP 1 LAST CUSTOM_TXT_CDS <CON_TC_SNO93>
J 2
(1100 2175);
FORCEPROP 1 LAST CUSTOM_TXT_CDS <CON_TC_SNO92>
J 2
(1100 2275);
FORCEPROP 1 LAST CUSTOM_TXT_CDS <CON_TC_SNO91>
J 2
(1100 2375);
FORCEPROP 1 LAST CUSTOM_TXT_CDS <CON_TC_SNO90>
J 2
(1100 2475);
FORCEPROP 1 LAST CUSTOM_TXT_CDS <CON_TC_SNO89>
J 2
(1100 2575);
FORCEPROP 1 LAST CUSTOM_TXT_CDS <CON_TC_SNO88>
J 2
(1100 2675);
FORCEPROP 1 LAST CUSTOM_TXT_CDS <CON_TC_SNO87>
J 2
(1100 2775);
FORCEPROP 1 LAST CUSTOM_TXT_CDS <CON_TC_SNO86>
J 2
(1100 2875);
FORCEPROP 1 LAST CUSTOM_TXT_CDS <CON_TC_SNO85>
J 2
(1100 2975);
FORCEPROP 1 LAST CUSTOM_TXT_CDS <CON_TC_SNO84>
J 2
(1100 3075);
FORCEPROP 1 LAST CUSTOM_TXT_CDS <CON_TC_SNO83>
J 2
(1100 3175);
FORCEPROP 1 LAST CUSTOM_TXT_CDS <CON_TC_SNO82>
J 2
(1100 3275);
FORCEPROP 1 LAST CUSTOM_TXT_CDS <CON_TC_SNO81>
J 2
(1100 3375);
FORCEPROP 1 LAST CUSTOM_TXT_CDS <CON_TC_SNO80>
J 2
(-1400 -525);
FORCEPROP 1 LAST CUSTOM_TXT_CDS <CON_TC_SNO79>
J 2
(-1400 -425);
FORCEPROP 1 LAST CUSTOM_TXT_CDS <CON_TC_SNO78>
J 2
(-1400 -325);
FORCEPROP 1 LAST CUSTOM_TXT_CDS <CON_TC_SNO77>
J 2
(-1400 -225);
FORCEPROP 1 LAST CUSTOM_TXT_CDS <CON_TC_SNO76>
J 2
(-1400 -125);
FORCEPROP 1 LAST CUSTOM_TXT_CDS <CON_TC_SNO75>
J 2
(-1400 -25);
FORCEPROP 1 LAST CUSTOM_TXT_CDS <CON_TC_SNO74>
J 2
(-1400 75);
FORCEPROP 1 LAST CUSTOM_TXT_CDS <CON_TC_SNO73>
J 2
(-1400 175);
FORCEPROP 1 LAST CUSTOM_TXT_CDS <CON_TC_SNO72>
J 2
(-1400 275);
FORCEPROP 1 LAST CUSTOM_TXT_CDS <CON_TC_SNO70>
J 2
(-1400 475);
FORCEPROP 1 LAST CUSTOM_TXT_CDS <CON_TC_SNO69>
J 2
(-1400 575);
FORCEPROP 1 LAST CUSTOM_TXT_CDS <CON_TC_SNO68>
J 2
(-1400 675);
FORCEPROP 1 LAST CUSTOM_TXT_CDS <CON_TC_SNO67>
J 2
(-1400 775);
FORCEPROP 1 LAST CUSTOM_TXT_CDS <CON_TC_SNO66>
J 2
(-1400 875);
FORCEPROP 1 LAST CUSTOM_TXT_CDS <CON_TC_SNO65>
J 2
(-1400 975);
FORCEPROP 1 LAST CUSTOM_TXT_CDS <CON_TC_SNO64>
J 2
(-1400 1075);
FORCEPROP 1 LAST CUSTOM_TXT_CDS <CON_TC_SNO63>
J 2
(-1400 1175);
FORCEPROP 1 LAST CUSTOM_TXT_CDS <CON_TC_SNO62>
J 2
(-1400 1275);
FORCEPROP 1 LAST CUSTOM_TXT_CDS <CON_TC_SNO61>
J 2
(-1400 1375);
FORCEPROP 1 LAST CUSTOM_TXT_CDS <CON_TC_SNO60>
J 2
(-1400 1475);
FORCEPROP 1 LAST CUSTOM_TXT_CDS <CON_TC_SNO59>
J 2
(-1400 1575);
FORCEPROP 1 LAST CUSTOM_TXT_CDS <CON_TC_SNO58>
J 2
(-1400 1675);
FORCEPROP 1 LAST CUSTOM_TXT_CDS <CON_TC_SNO57>
J 2
(-1400 1775);
FORCEPROP 1 LAST CUSTOM_TXT_CDS <CON_TC_SNO56>
J 2
(-1400 1875);
FORCEPROP 1 LAST CUSTOM_TXT_CDS <CON_TC_SNO55>
J 2
(-1400 1975);
FORCEPROP 1 LAST CUSTOM_TXT_CDS <CON_TC_SNO54>
J 2
(-1400 2075);
FORCEPROP 1 LAST CUSTOM_TXT_CDS <CON_TC_SNO53>
J 2
(-1400 2175);
FORCEPROP 1 LAST CUSTOM_TXT_CDS <CON_TC_SNO52>
J 2
(-1400 2275);
FORCEPROP 1 LAST CUSTOM_TXT_CDS <CON_TC_SNO51>
J 2
(-1400 2375);
FORCEPROP 1 LAST CUSTOM_TXT_CDS <CON_TC_SNO50>
J 2
(-1400 2475);
FORCEPROP 1 LAST CUSTOM_TXT_CDS <CON_TC_SNO49>
J 2
(-1400 2575);
FORCEPROP 1 LAST CUSTOM_TXT_CDS <CON_TC_SNO48>
J 2
(-1400 2675);
FORCEPROP 1 LAST CUSTOM_TXT_CDS <CON_TC_SNO47>
J 2
(-1400 2775);
FORCEPROP 1 LAST CUSTOM_TXT_CDS <CON_TC_SNM120>
J 0
(1200 -525);
FORCEPROP 1 LAST CUSTOM_TXT_CDS <CON_TC_SNM119>
J 0
(1200 -425);
FORCEPROP 1 LAST CUSTOM_TXT_CDS <CON_TC_SNM118>
J 0
(1200 -325);
FORCEPROP 1 LAST CUSTOM_TXT_CDS <CON_TC_SNM117>
J 0
(1200 -225);
FORCEPROP 1 LAST CUSTOM_TXT_CDS <CON_TC_SNM116>
J 0
(1200 -125);
FORCEPROP 1 LAST CUSTOM_TXT_CDS <CON_TC_SNM115>
J 0
(1200 -25);
FORCEPROP 1 LAST CUSTOM_TXT_CDS <CON_TC_SNM114>
J 0
(1200 75);
FORCEPROP 1 LAST CUSTOM_TXT_CDS <CON_TC_SNM113>
J 0
(1200 175);
FORCEPROP 1 LAST CUSTOM_TXT_CDS <CON_TC_SNM112>
J 0
(1200 275);
FORCEPROP 1 LAST CUSTOM_TXT_CDS <CON_TC_SNM111>
J 0
(1200 375);
FORCEPROP 1 LAST CUSTOM_TXT_CDS <CON_TC_SNM109>
J 0
(1200 575);
FORCEPROP 1 LAST CUSTOM_TXT_CDS <CON_TC_SNM107>
J 0
(1200 775);
FORCEPROP 1 LAST CUSTOM_TXT_CDS <CON_TC_SNM106>
J 0
(1200 875);
FORCEPROP 1 LAST CUSTOM_TXT_CDS <CON_TC_SNM105>
J 0
(1200 975);
FORCEPROP 1 LAST CUSTOM_TXT_CDS <CON_TC_SNM104>
J 0
(1200 1075);
FORCEPROP 1 LAST CUSTOM_TXT_CDS <CON_TC_SNM103>
J 0
(1200 1175);
FORCEPROP 1 LAST CUSTOM_TXT_CDS <CON_TC_SNM102>
J 0
(1200 1275);
FORCEPROP 1 LAST CUSTOM_TXT_CDS <CON_TC_SNM101>
J 0
(1200 1375);
FORCEPROP 1 LAST CUSTOM_TXT_CDS <CON_TC_SNM100>
J 0
(1200 1475);
FORCEPROP 1 LAST CUSTOM_TXT_CDS <CON_TC_SNM99>
J 0
(1200 1575);
FORCEPROP 1 LAST CUSTOM_TXT_CDS <CON_TC_SNM98>
J 0
(1200 1675);
FORCEPROP 1 LAST CUSTOM_TXT_CDS <CON_TC_SNM97>
J 0
(1200 1775);
FORCEPROP 1 LAST CUSTOM_TXT_CDS <CON_TC_SNM96>
J 0
(1200 1875);
FORCEPROP 1 LAST CUSTOM_TXT_CDS <CON_TC_SNM95>
J 0
(1200 1975);
FORCEPROP 1 LAST CUSTOM_TXT_CDS <CON_TC_SNM94>
J 0
(1200 2075);
FORCEPROP 1 LAST CUSTOM_TXT_CDS <CON_TC_SNM93>
J 0
(1200 2175);
FORCEPROP 1 LAST CUSTOM_TXT_CDS <CON_TC_SNM92>
J 0
(1200 2275);
FORCEPROP 1 LAST CUSTOM_TXT_CDS <CON_TC_SNM91>
J 0
(1200 2375);
FORCEPROP 1 LAST CUSTOM_TXT_CDS <CON_TC_SNM90>
J 0
(1200 2475);
FORCEPROP 1 LAST CUSTOM_TXT_CDS <CON_TC_SNM89>
J 0
(1200 2575);
FORCEPROP 1 LAST CUSTOM_TXT_CDS <CON_TC_SNM88>
J 0
(1200 2675);
FORCEPROP 1 LAST CUSTOM_TXT_CDS <CON_TC_SNM87>
J 0
(1200 2775);
FORCEPROP 1 LAST CUSTOM_TXT_CDS <CON_TC_SNM86>
J 0
(1200 2875);
FORCEPROP 1 LAST CUSTOM_TXT_CDS <CON_TC_SNM85>
J 0
(1200 2975);
FORCEPROP 1 LAST CUSTOM_TXT_CDS <CON_TC_SNM84>
J 0
(1200 3075);
FORCEPROP 1 LAST CUSTOM_TXT_CDS <CON_TC_SNM83>
J 0
(1200 3175);
FORCEPROP 1 LAST CUSTOM_TXT_CDS <CON_TC_SNM82>
J 0
(1200 3275);
FORCEPROP 1 LAST CUSTOM_TXT_CDS <CON_TC_SNM81>
J 0
(1200 3375);
FORCEPROP 1 LAST CUSTOM_TXT_CDS <CON_TC_SNM80>
J 0
(-1300 -525);
FORCEPROP 1 LAST CUSTOM_TXT_CDS <CON_TC_SNM79>
J 0
(-1300 -425);
FORCEPROP 1 LAST CUSTOM_TXT_CDS <CON_TC_SNM78>
J 0
(-1300 -325);
FORCEPROP 1 LAST CUSTOM_TXT_CDS <CON_TC_SNM77>
J 0
(-1300 -225);
FORCEPROP 1 LAST CUSTOM_TXT_CDS <CON_TC_SNM76>
J 0
(-1300 -125);
FORCEPROP 1 LAST CUSTOM_TXT_CDS <CON_TC_SNM75>
J 0
(-1300 -25);
FORCEPROP 1 LAST CUSTOM_TXT_CDS <CON_TC_SNM74>
J 0
(-1300 75);
FORCEPROP 1 LAST CUSTOM_TXT_CDS <CON_TC_SNM73>
J 0
(-1300 175);
FORCEPROP 1 LAST CUSTOM_TXT_CDS <CON_TC_SNM72>
J 0
(-1300 275);
FORCEPROP 1 LAST CUSTOM_TXT_CDS <CON_TC_SNM70>
J 0
(-1300 475);
FORCEPROP 1 LAST CUSTOM_TXT_CDS <CON_TC_SNM64>
J 0
(-1300 1075);
FORCEPROP 1 LAST CUSTOM_TXT_CDS <CON_TC_SNM63>
J 0
(-1300 1175);
FORCEPROP 1 LAST CUSTOM_TXT_CDS <CON_TC_SNM62>
J 0
(-1300 1275);
FORCEPROP 1 LAST CUSTOM_TXT_CDS <CON_TC_SNM61>
J 0
(-1300 1375);
FORCEPROP 1 LAST CUSTOM_TXT_CDS <CON_TC_SNM60>
J 0
(-1300 1475);
FORCEPROP 1 LAST CUSTOM_TXT_CDS <CON_TC_SNM59>
J 0
(-1300 1575);
FORCEPROP 1 LAST CUSTOM_TXT_CDS <CON_TC_SNM58>
J 0
(-1300 1675);
FORCEPROP 1 LAST CUSTOM_TXT_CDS <CON_TC_SNM57>
J 0
(-1300 1775);
FORCEPROP 1 LAST CUSTOM_TXT_CDS <CON_TC_SNM56>
J 0
(-1300 1875);
FORCEPROP 1 LAST CUSTOM_TXT_CDS <CON_TC_SNM55>
J 0
(-1300 1975);
FORCEPROP 1 LAST CUSTOM_TXT_CDS <CON_TC_SNM54>
J 0
(-1300 2075);
FORCEPROP 1 LAST CUSTOM_TXT_CDS <CON_TC_SNM53>
J 0
(-1300 2175);
FORCEPROP 1 LAST CUSTOM_TXT_CDS <CON_TC_SNM52>
J 0
(-1300 2275);
FORCEPROP 1 LAST CUSTOM_TXT_CDS <CON_TC_SNM51>
J 0
(-1300 2375);
FORCEPROP 1 LAST CUSTOM_TXT_CDS <CON_TC_SNM50>
J 0
(-1300 2475);
FORCEPROP 1 LAST CUSTOM_TXT_CDS <CON_TC_SNM49>
J 0
(-1300 2575);
FORCEPROP 1 LAST CUSTOM_TXT_CDS <CON_TC_SNM48>
J 0
(-1300 2675);
FORCEPROP 1 LAST CUSTOM_TXT_CDS <CON_TC_SNM47>
J 0
(-1300 2775);
FORCEPROP 1 LAST CUSTOM_TXT_CDS <CON_LAST_MODIFIED>
J 0
(1900 -2175);
DISPLAY 0.978723 (1900 -2175);
FORCEPROP 1 LAST CUSTOM_TXT_CDS <CON_TC_SNO46>
J 2
(-1400 2875);
FORCEPROP 1 LAST CUSTOM_TXT_CDS <CON_TC_SNO45>
J 2
(-1400 2975);
FORCEPROP 1 LAST CUSTOM_TXT_CDS <CON_TC_SNO44>
J 2
(-1400 3075);
FORCEPROP 1 LAST CUSTOM_TXT_CDS <CON_TC_SNO43>
J 2
(-1400 3175);
FORCEPROP 1 LAST CUSTOM_TXT_CDS <CON_TC_SNO42>
J 2
(-1400 3275);
FORCEPROP 1 LAST CUSTOM_TXT_CDS <CON_TC_SNO41>
J 2
(-1400 3375);
FORCEPROP 1 LAST CUSTOM_TXT_CDS <CON_TC_SNO40>
J 2
(-3900 -525);
FORCEPROP 1 LAST CUSTOM_TXT_CDS <CON_TC_SNO39>
J 2
(-3900 -425);
FORCEPROP 1 LAST CUSTOM_TXT_CDS <CON_TC_SNO38>
J 2
(-3900 -325);
FORCEPROP 1 LAST CUSTOM_TXT_CDS <CON_TC_SNO37>
J 2
(-3900 -225);
FORCEPROP 1 LAST CUSTOM_TXT_CDS <CON_TC_SNO36>
J 2
(-3900 -125);
FORCEPROP 1 LAST CUSTOM_TXT_CDS <CON_TC_SNO35>
J 2
(-3900 -25);
FORCEPROP 1 LAST CUSTOM_TXT_CDS <CON_TC_SNO34>
J 2
(-3900 75);
FORCEPROP 1 LAST CUSTOM_TXT_CDS <CON_TC_SNO33>
J 2
(-3900 175);
FORCEPROP 1 LAST CUSTOM_TXT_CDS <CON_TC_SNO32>
J 2
(-3900 275);
FORCEPROP 1 LAST CUSTOM_TXT_CDS <CON_TC_SNO31>
J 2
(-3900 375);
FORCEPROP 1 LAST CUSTOM_TXT_CDS <CON_TC_SNO30>
J 2
(-3900 475);
FORCEPROP 1 LAST CUSTOM_TXT_CDS <CON_TC_SNO29>
J 2
(-3900 575);
FORCEPROP 1 LAST CUSTOM_TXT_CDS <CON_TC_SNO28>
J 2
(-3900 675);
FORCEPROP 1 LAST CUSTOM_TXT_CDS <CON_TC_SNO27>
J 2
(-3900 775);
FORCEPROP 1 LAST CUSTOM_TXT_CDS <CON_TC_SNO25>
J 2
(-3900 975);
FORCEPROP 1 LAST CUSTOM_TXT_CDS <CON_TC_SNO24>
J 2
(-3900 1075);
FORCEPROP 1 LAST CUSTOM_TXT_CDS <CON_TC_SNO23>
J 2
(-3900 1175);
FORCEPROP 1 LAST CUSTOM_TXT_CDS <CON_TC_SNO22>
J 2
(-3900 1275);
FORCEPROP 1 LAST CUSTOM_TXT_CDS <CON_TC_SNO21>
J 2
(-3900 1375);
FORCEPROP 1 LAST CUSTOM_TXT_CDS <CON_TC_SNO20>
J 2
(-3900 1475);
FORCEPROP 1 LAST CUSTOM_TXT_CDS <CON_TC_SNO19>
J 2
(-3900 1575);
FORCEPROP 1 LAST CUSTOM_TXT_CDS <CON_TC_SNO18>
J 2
(-3900 1675);
FORCEPROP 1 LAST CUSTOM_TXT_CDS <CON_TC_SNO17>
J 2
(-3900 1775);
FORCEPROP 1 LAST CUSTOM_TXT_CDS <CON_TC_SNO16>
J 2
(-3900 1875);
FORCEPROP 1 LAST CUSTOM_TXT_CDS <CON_TC_SNO15>
J 2
(-3900 1975);
FORCEPROP 1 LAST CUSTOM_TXT_CDS <CON_TC_SNO14>
J 2
(-3900 2075);
FORCEPROP 1 LAST CUSTOM_TXT_CDS <CON_TC_SNO13>
J 2
(-3900 2175);
FORCEPROP 1 LAST CUSTOM_TXT_CDS <CON_TC_SNO12>
J 2
(-3900 2275);
FORCEPROP 1 LAST CUSTOM_TXT_CDS <CON_TC_SNO11>
J 2
(-3900 2375);
FORCEPROP 1 LAST CUSTOM_TXT_CDS <CON_TC_SNO10>
J 2
(-3900 2475);
FORCEPROP 1 LAST CUSTOM_TXT_CDS <CON_TC_SNO9>
J 2
(-3900 2575);
FORCEPROP 1 LAST CUSTOM_TXT_CDS <CON_TC_SNO8>
J 2
(-3900 2675);
FORCEPROP 1 LAST CUSTOM_TXT_CDS <CON_TC_SNO7>
J 2
(-3900 2775);
FORCEPROP 1 LAST CUSTOM_TXT_CDS <CON_TC_SNO6>
J 2
(-3900 2875);
FORCEPROP 1 LAST CUSTOM_TXT_CDS <CON_TC_SNO5>
J 2
(-3900 2975);
FORCEPROP 1 LAST CUSTOM_TXT_CDS <CON_TC_SNO4>
J 2
(-3900 3075);
FORCEPROP 1 LAST CUSTOM_TXT_CDS <CON_TC_SNO3>
J 2
(-3900 3175);
FORCEPROP 1 LAST CUSTOM_TXT_CDS <CON_TC_SNO2>
J 2
(-3900 3275);
FORCEPROP 1 LAST CUSTOM_TXT_CDS <CON_TC_SNO1>
J 2
(-3900 3375);
FORCEPROP 1 LAST CUSTOM_TXT_CDS <CON_TC_SNM46>
J 0
(-1300 2875);
FORCEPROP 1 LAST CUSTOM_TXT_CDS <CON_TC_SNM45>
J 0
(-1300 2975);
FORCEPROP 1 LAST CUSTOM_TXT_CDS <CON_TC_SNM44>
J 0
(-1300 3075);
FORCEPROP 1 LAST CUSTOM_TXT_CDS <CON_TC_SNM43>
J 0
(-1300 3175);
FORCEPROP 1 LAST CUSTOM_TXT_CDS <CON_TC_SNM42>
J 0
(-1300 3275);
FORCEPROP 1 LAST CUSTOM_TXT_CDS <CON_TC_SNM41>
J 0
(-1300 3375);
FORCEPROP 1 LAST CUSTOM_TXT_CDS <CON_TC_SNM40>
J 0
(-3800 -525);
FORCEPROP 1 LAST CUSTOM_TXT_CDS <CON_TC_SNM39>
J 0
(-3800 -425);
FORCEPROP 1 LAST CUSTOM_TXT_CDS <CON_TC_SNM38>
J 0
(-3800 -325);
FORCEPROP 1 LAST CUSTOM_TXT_CDS <CON_TC_SNM37>
J 0
(-3800 -225);
FORCEPROP 1 LAST CUSTOM_TXT_CDS <CON_TC_SNM36>
J 0
(-3800 -125);
FORCEPROP 1 LAST CUSTOM_TXT_CDS <CON_TC_SNM35>
J 0
(-3800 -25);
FORCEPROP 1 LAST CUSTOM_TXT_CDS <CON_TC_SNM34>
J 0
(-3800 75);
FORCEPROP 1 LAST CUSTOM_TXT_CDS <CON_TC_SNM33>
J 0
(-3800 175);
FORCEPROP 1 LAST CUSTOM_TXT_CDS <CON_TC_SNM32>
J 0
(-3800 275);
FORCEPROP 1 LAST CUSTOM_TXT_CDS <CON_TC_SNM31>
J 0
(-3800 375);
FORCEPROP 1 LAST CUSTOM_TXT_CDS <CON_TC_SNM26>
J 0
(-3800 875);
FORCEPROP 1 LAST CUSTOM_TXT_CDS <CON_TC_SNM25>
J 0
(-3800 975);
FORCEPROP 1 LAST CUSTOM_TXT_CDS <CON_TC_SNM24>
J 0
(-3800 1075);
FORCEPROP 1 LAST CUSTOM_TXT_CDS <CON_TC_SNM23>
J 0
(-3800 1175);
FORCEPROP 1 LAST CUSTOM_TXT_CDS <CON_TC_SNM22>
J 0
(-3800 1275);
FORCEPROP 1 LAST CUSTOM_TXT_CDS <CON_TC_SNM21>
J 0
(-3800 1375);
FORCEPROP 1 LAST CUSTOM_TXT_CDS <CON_TC_SNM20>
J 0
(-3800 1475);
FORCEPROP 1 LAST CUSTOM_TXT_CDS <CON_TC_SNM19>
J 0
(-3800 1575);
FORCEPROP 1 LAST CUSTOM_TXT_CDS <CON_TC_SNM18>
J 0
(-3800 1675);
FORCEPROP 1 LAST CUSTOM_TXT_CDS <CON_TC_SNM17>
J 0
(-3800 1775);
FORCEPROP 1 LAST CUSTOM_TXT_CDS <CON_TC_SNM16>
J 0
(-3800 1875);
FORCEPROP 1 LAST CUSTOM_TXT_CDS <CON_TC_SNM15>
J 0
(-3800 1975);
FORCEPROP 1 LAST CUSTOM_TXT_CDS <CON_TC_SNM14>
J 0
(-3800 2075);
FORCEPROP 1 LAST CUSTOM_TXT_CDS <CON_TC_SNM13>
J 0
(-3800 2175);
FORCEPROP 1 LAST CUSTOM_TXT_CDS <CON_TC_SNM12>
J 0
(-3800 2275);
FORCEPROP 1 LAST CUSTOM_TXT_CDS <CON_TC_SNM11>
J 0
(-3800 2375);
FORCEPROP 1 LAST CUSTOM_TXT_CDS <CON_TC_SNM10>
J 0
(-3800 2475);
FORCEPROP 1 LAST CUSTOM_TXT_CDS <CON_TC_SNM9>
J 0
(-3800 2575);
FORCEPROP 1 LAST CUSTOM_TXT_CDS <CON_TC_SNM8>
J 0
(-3800 2675);
FORCEPROP 1 LAST CUSTOM_TXT_CDS <CON_TC_SNM7>
J 0
(-3800 2775);
FORCEPROP 1 LAST CUSTOM_TXT_CDS <CON_TC_SNM6>
J 0
(-3800 2875);
FORCEPROP 1 LAST CUSTOM_TXT_CDS <CON_TC_SNM5>
J 0
(-3800 2975);
FORCEPROP 1 LAST CUSTOM_TXT_CDS <CON_TC_SNM4>
J 0
(-3800 3075);
FORCEPROP 1 LAST CUSTOM_TXT_CDS <CON_TC_SNM3>
J 0
(-3800 3175);
FORCEPROP 1 LAST CUSTOM_TXT_CDS <CON_TC_SNM2>
J 0
(-3800 3275);
FORCEPROP 1 LAST CUSTOM_TXT_CDS <CON_TC_SNM1>
J 0
(-3800 3375);
FORCEPROP 1 LAST CUSTOM_TXT_CDS <CON_TC_SNO26>
J 2
(-3900 875);
FORCEPROP 1 LAST CUSTOM_TXT_CDS <CON_TC_SNM27>
J 0
(-3800 775);
FORCEPROP 1 LAST CUSTOM_TXT_CDS <CON_TC_SNM28>
J 0
(-3800 675);
FORCEPROP 1 LAST CUSTOM_TXT_CDS <CON_TC_SNM29>
J 0
(-3800 575);
FORCEPROP 1 LAST CUSTOM_TXT_CDS <CON_TC_SNM30>
J 0
(-3800 475);
FORCEPROP 1 LAST CUSTOM_TXT_CDS <CON_TC_SNO71>
J 2
(-1400 375);
FORCEPROP 1 LAST CUSTOM_TXT_CDS <CON_TC_SNM108>
J 0
(1200 675);
FORCEPROP 1 LAST CUSTOM_TXT_CDS <CON_TC_SNM71>
J 0
(-1300 375);
FORCEPROP 1 LAST CUSTOM_TXT_CDS <CON_TC_SNM110>
J 0
(1200 475);
FORCEPROP 1 LAST CUSTOM_TXT_CDS <CON_TC_SNM69>
J 0
(-1300 575);
FORCEPROP 1 LAST CUSTOM_TXT_CDS <CON_TC_SNM68>
J 0
(-1300 675);
FORCEPROP 1 LAST CUSTOM_TXT_CDS <CON_TC_SNM67>
J 0
(-1300 775);
FORCEPROP 1 LAST CUSTOM_TXT_CDS <CON_TC_SNM66>
J 0
(-1300 875);
FORCEPROP 1 LAST CUSTOM_TXT_CDS <CON_TC_SNM65>
J 0
(-1300 975);
FORCEPROP 2 LAST Q_DEPT 
J 1
(49 -2151);
DISPLAY 1.957447 (49 -2151);
PAINT GREEN (49 -2151);
FORCEPROP 2 LAST PAGE_BORDER TRUE
J 0
(-4090 3050);
DISPLAY 0.638298 (-4090 3050);
PAINT PINK (-4090 3050);
DISPLAY INVISIBLE (-4090 3050);
FORCEPROP 1 LAST TOC_SYMBOL TRUE
J 0
(-5374 4252);
DISPLAY 0.978723 (-5374 4252);
PAINT GREEN (-5374 4252);
DISPLAY INVISIBLE (-5374 4252);
FORCEPROP 1 LAST COMMENT_BODY TRUE
J 0
(2651 -2174);
DISPLAY 0.978723 (2651 -2174);
PAINT GREEN (2651 -2174);
DISPLAY INVISIBLE (2651 -2174);
FORCEPROP 2 LAST CDS_LIB pure_quanta
J 0
(3800 -2200);
PAINT MONO (3800 -2200);
DISPLAY INVISIBLE (3800 -2200);
FORCEPROP 2 LAST CDS_XR_PAGE_TITLE CR-3 : @S9S_MB_2U_LIB.S9S_MB_2U(SCH_1):PAGE3
J 0
(-4090 3050);
DISPLAY 0.638298 (-4090 3050);
PAINT PINK (-4090 3050);
DISPLAY INVISIBLE (-4090 3050);
FORCEPROP 2 LAST CUSTOM_TXT_CDS <XR_PAGE_TITLE>
J 0
(-4090 3050);
DISPLAY 0.638298 (-4090 3050);
PAINT PINK (-4090 3050);
DISPLAY INVISIBLE (-4090 3050);
FORCEPROP 0 LAST CDS_CON_LAST_MODIFIED Thu Aug 24 16:11:56 2023
J 0
(1900 -2175);
PAINT MONO (1900 -2175);
DISPLAY INVISIBLE (1900 -2175);
QUIT
